# S9S_MB_2U (Grand Teton) — schematic netlist excerpt (pin names and nets, part order shuffled) for the footprints in the layout excerpt that follows; sources: Cadence DE-HDL packaged netlist, KiCad conversion of 03242023_DA0F0TMBIJ0_F0T_Motherboard_J_brd_V01_OCP.brd

PL22  Q_INDUCTOR  120NH/69A IND  pkg SMLF  page 293 : \1\ = SW_PVCCINFAON_CPU1_SW2 ; \2\ = PVCCINFAON_CPU1

U210  74LVC1G08W57  74LVC1G08W5-7 IC  pkg SOT25-5_0-95_3X1-6  page 158
  A  = HP_LVC3_OCP_V3_1_PWRGD_R
  B  = RST_OCP_V3_1_N
  GND  = GND
  Y  = RST_HP_OCP_V3_1_N
  VCC  = P3V3_AUX

C1575  Q_CAP_DIFFBUS  DIFF BUS_0.22UF 6.3V 20% X6S  pkg C0201  page 175 : \1\ = P5E_CPU0_PE4_TX_C_DP<2> ; \2\ = P5E_CPU0_PE4_TX_DP<2>
C697  Q_CAP_DIFFBUS  DIFF BUS_0.22UF 6.3V 20% X6S  pkg C0201  page 177 : \1\ = P5E_CPU1_PE4_TX_C_DP<6> ; \2\ = P5E_CPU1_PE4_TX_DP<6>

(kicad_pcb
	(version 20260206)
	(generator "pcbnew")
	(generator_version "10.0")
	(general
		(thickness 1.6)
		(legacy_teardrops no)
	)
	(paper "A4")
	(title_block
		(title "03242023_DA0F0TMBIJ0_F0T_Motherboard_J_brd_V01_OCP.brd")
		(comment 1 "Grand Teton / footprints 1430-1433 of 6105")
	)
	(layers
		(0 "F.Cu" signal "TOP")
		(4 "In1.Cu" signal "GND")
		(6 "In2.Cu" signal "IN1")
		(8 "In3.Cu" signal "GND1")
		(10 "In4.Cu" signal "IN2")
		(12 "In5.Cu" signal "GND2")
		(14 "In6.Cu" signal "IN3")
		(16 "In7.Cu" signal "GND3")
		(18 "In8.Cu" signal "VCC")
		(20 "In9.Cu" signal "VCC1")
		(22 "In10.Cu" signal "GND4")
		(24 "In11.Cu" signal "IN4")
		(26 "In12.Cu" signal "GND5")
		(28 "In13.Cu" signal "IN5")
		(30 "In14.Cu" signal "GND6")
		(32 "In15.Cu" signal "IN6")
		(34 "In16.Cu" signal "GND7")
		(2 "B.Cu" signal "BOTTOM")
		(9 "F.Adhes" user "F.Adhesive")
		(11 "B.Adhes" user "B.Adhesive")
		(13 "F.Paste" user "Package Geometry/Pastemask Top")
		(15 "B.Paste" user "Package Geometry/Pastemask Bottom")
		(5 "F.SilkS" user "Ref Des/Silkscreen Top")
		(7 "B.SilkS" user "Ref Des/Silkscreen Bottom")
		(1 "F.Mask" user "Board Geometry/Soldermask Top")
		(3 "B.Mask" user "Board Geometry/Soldermask Bottom")
		(17 "Dwgs.User" user "User.Drawings")
		(19 "Cmts.User" user "User.Comments")
		(21 "Eco1.User" user "User.Eco1")
		(23 "Eco2.User" user "User.Eco2")
		(25 "Edge.Cuts" user "Board Geometry/Outline")
		(27 "Margin" user)
		(31 "F.CrtYd" user "Package Geometry/Place Bound Top")
		(29 "B.CrtYd" user "Package Geometry/Place Bound Bottom")
		(35 "F.Fab" user "Ref Des/Assembly Top")
		(33 "B.Fab" user "Ref Des/Assembly Bottom")
	)
	(footprint ""
		(layer "F.Cu")
		(at 392.719814 -36.318698 90)
		(property "Reference" "U210"
			(at 0.01016 2.864866 0)
			(unlocked yes)
			(layer "F.SilkS")
			(effects
				(font
					(size 0.7874 0.5842)
					(thickness 0.1524)
				)
				(justify left)
			)
		)
		(property "Value" ""
			(at 0 0 90)
			(layer "F.Fab")
			(effects
				(font
					(size 1.27 1.27)
				)
			)
		)
		(duplicate_pad_numbers_are_jumpers no)
		(fp_line
			(start 1.733296 -1.549908)
			(end 0.660908 -1.549908)
			(stroke
				(width 0.1524)
				(type default)
			)
			(layer "F.SilkS")
		)
		(fp_line
			(start 0.660908 -1.549908)
			(end 0 -0.889)
			(stroke
				(width 0.1524)
				(type default)
			)
			(layer "F.SilkS")
		)
		(fp_line
			(start -0.660908 -1.549908)
			(end -1.733296 -1.549908)
			(stroke
				(width 0.1524)
				(type default)
			)
			(layer "F.SilkS")
		)
		(fp_line
			(start -1.733296 -1.549908)
			(end -1.733296 1.549908)
			(stroke
				(width 0.1524)
				(type default)
			)
			(layer "F.SilkS")
		)
		(fp_line
			(start 0 -0.889)
			(end -0.660908 -1.549908)
			(stroke
				(width 0.1524)
				(type default)
			)
			(layer "F.SilkS")
		)
		(fp_line
			(start 1.733296 1.549908)
			(end 1.733296 -1.549908)
			(stroke
				(width 0.1524)
				(type default)
			)
			(layer "F.SilkS")
		)
		(fp_line
			(start -1.733296 1.549908)
			(end 1.733296 1.549908)
			(stroke
				(width 0.1524)
				(type default)
			)
			(layer "F.SilkS")
		)
		(fp_poly
			(pts
				(xy -1.9304 -0.94996) (xy -2.4384 -0.69596) (xy -2.4384 -1.20396)
			)
			(stroke
				(width 0)
				(type default)
			)
			(fill yes)
			(layer "F.SilkS")
		)
		(fp_line
			(start 0.849884 -1.549908)
			(end -0.849884 -1.549908)
			(stroke
				(width 0.1)
				(type default)
			)
			(layer "F.Fab")
		)
		(fp_line
			(start -0.849884 -1.549908)
			(end -0.849884 1.549908)
			(stroke
				(width 0.1)
				(type default)
			)
			(layer "F.Fab")
		)
		(fp_line
			(start 0.849884 1.549908)
			(end 0.849884 -1.549908)
			(stroke
				(width 0.1)
				(type default)
			)
			(layer "F.Fab")
		)
		(fp_line
			(start -0.849884 1.549908)
			(end 0.849884 1.549908)
			(stroke
				(width 0.1)
				(type default)
			)
			(layer "F.Fab")
		)
		(fp_poly
			(pts
				(xy -2.4384 -1.20396) (xy -2.4384 -0.69596) (xy -1.9304 -0.94996)
			)
			(stroke
				(width 0)
				(type default)
			)
			(fill yes)
			(layer "F.Fab")
		)
		(pad "1" smd rect
			(at -1.199896 -0.94996)
			(size 0.5588 0.8128)
			(layers "F.Cu" "F.Mask" "F.Paste")
			(net "HP_LVC3_OCP_V3_1_PWRGD_R")
		)
		(pad "2" smd rect
			(at -1.199896 0)
			(size 0.5588 0.8128)
			(layers "F.Cu" "F.Mask" "F.Paste")
			(net "RST_OCP_V3_1_N")
		)
		(pad "3" smd rect
			(at -1.199896 0.94996)
			(size 0.5588 0.8128)
			(layers "F.Cu" "F.Mask" "F.Paste")
			(net "GND")
		)
		(pad "4" smd rect
			(at 1.199896 0.94996)
			(size 0.5588 0.8128)
			(layers "F.Cu" "F.Mask" "F.Paste")
			(net "RST_HP_OCP_V3_1_N")
		)
		(pad "5" smd rect
			(at 1.199896 -0.94996)
			(size 0.5588 0.8128)
			(layers "F.Cu" "F.Mask" "F.Paste")
			(net "P3V3_AUX")
		)
	)
	(footprint ""
		(layer "F.Cu")
		(at 68.594478 -408.517344 -90)
		(property "Reference" "C697"
			(at 0 0 270)
			(layer "F.SilkS")
			(hide yes)
			(effects
				(font
					(size 1.27 1.27)
				)
			)
		)
		(property "Value" ""
			(at 0 0 270)
			(layer "F.Fab")
			(effects
				(font
					(size 1.27 1.27)
				)
			)
		)
		(duplicate_pad_numbers_are_jumpers no)
		(fp_line
			(start -0.299974 0.150114)
			(end -0.299974 -0.150114)
			(stroke
				(width 0.1)
				(type default)
			)
			(layer "F.Fab")
		)
		(fp_line
			(start 0.299974 0.150114)
			(end -0.299974 0.150114)
			(stroke
				(width 0.1)
				(type default)
			)
			(layer "F.Fab")
		)
		(fp_line
			(start -0.299974 -0.150114)
			(end 0.299974 -0.150114)
			(stroke
				(width 0.1)
				(type default)
			)
			(layer "F.Fab")
		)
		(fp_line
			(start 0.299974 -0.150114)
			(end 0.299974 0.150114)
			(stroke
				(width 0.1)
				(type default)
			)
			(layer "F.Fab")
		)
		(pad "1" smd rect
			(at -0.2667 0 270)
			(size 0.3048 0.381)
			(layers "F.Cu" "F.Mask" "F.Paste")
			(net "P5E_CPU1_PE4_TX_C_DP<6>")
		)
		(pad "2" smd rect
			(at 0.2667 0 270)
			(size 0.3048 0.381)
			(layers "F.Cu" "F.Mask" "F.Paste")
			(net "P5E_CPU1_PE4_TX_DP<6>")
		)
	)
	(footprint ""
		(layer "F.Cu")
		(at 310.995568 -402.371052 -90)
		(property "Reference" "C1575"
			(at 0 0 270)
			(layer "F.SilkS")
			(hide yes)
			(effects
				(font
					(size 1.27 1.27)
				)
			)
		)
		(property "Value" ""
			(at 0 0 270)
			(layer "F.Fab")
			(effects
				(font
					(size 1.27 1.27)
				)
			)
		)
		(duplicate_pad_numbers_are_jumpers no)
		(fp_line
			(start -0.299974 0.150114)
			(end -0.299974 -0.150114)
			(stroke
				(width 0.1)
				(type default)
			)
			(layer "F.Fab")
		)
		(fp_line
			(start 0.299974 0.150114)
			(end -0.299974 0.150114)
			(stroke
				(width 0.1)
				(type default)
			)
			(layer "F.Fab")
		)
		(fp_line
			(start -0.299974 -0.150114)
			(end 0.299974 -0.150114)
			(stroke
				(width 0.1)
				(type default)
			)
			(layer "F.Fab")
		)
		(fp_line
			(start 0.299974 -0.150114)
			(end 0.299974 0.150114)
			(stroke
				(width 0.1)
				(type default)
			)
			(layer "F.Fab")
		)
		(pad "1" smd rect
			(at -0.2667 0 270)
			(size 0.3048 0.381)
			(layers "F.Cu" "F.Mask" "F.Paste")
			(net "P5E_CPU0_PE4_TX_C_DP<2>")
		)
		(pad "2" smd rect
			(at 0.2667 0 270)
			(size 0.3048 0.381)
			(layers "F.Cu" "F.Mask" "F.Paste")
			(net "P5E_CPU0_PE4_TX_DP<2>")
		)
	)
	(footprint ""
		(layer "F.Cu")
		(at 62.35446 -147.84197)
		(property "Reference" "PL22"
			(at -3.52044 -4.364228 0)
			(unlocked yes)
			(layer "F.SilkS")
			(effects
				(font
					(size 0.7874 0.5842)
					(thickness 0.1524)
				)
				(justify left)
			)
		)
		(property "Value" ""
			(at 0 0 0)
			(layer "F.Fab")
			(effects
				(font
					(size 1.27 1.27)
				)
			)
		)
		(duplicate_pad_numbers_are_jumpers no)
		(fp_line
			(start -3.24993 -3.24993)
			(end 3.24993 -3.24993)
			(stroke
				(width 0.1524)
				(type default)
			)
			(layer "F.SilkS")
		)
		(fp_line
			(start -3.24993 -2.2352)
			(end -3.24993 -3.24993)
			(stroke
				(width 0.1524)
				(type default)
			)
			(layer "F.SilkS")
		)
		(fp_line
			(start -3.24993 3.24993)
			(end -3.24993 2.2352)
			(stroke
				(width 0.1524)
				(type default)
			)
			(layer "F.SilkS")
		)
		(fp_line
			(start 3.24993 -3.24993)
			(end 3.24993 -2.2352)
			(stroke
				(width 0.1524)
				(type default)
			)
			(layer "F.SilkS")
		)
		(fp_line
			(start 3.24993 2.2352)
			(end 3.24993 3.24993)
			(stroke
				(width 0.1524)
				(type default)
			)
			(layer "F.SilkS")
		)
		(fp_line
			(start 3.24993 3.24993)
			(end -3.24993 3.24993)
			(stroke
				(width 0.1524)
				(type default)
			)
			(layer "F.SilkS")
		)
		(fp_line
			(start -3.24993 -3.24993)
			(end 3.24993 -3.24993)
			(stroke
				(width 0.1)
				(type default)
			)
			(layer "F.Fab")
		)
		(fp_line
			(start -3.24993 3.24993)
			(end -3.24993 -3.24993)
			(stroke
				(width 0.1)
				(type default)
			)
			(layer "F.Fab")
		)
		(fp_line
			(start 3.24993 -3.24993)
			(end 3.24993 3.24993)
			(stroke
				(width 0.1)
				(type default)
			)
			(layer "F.Fab")
		)
		(fp_line
			(start 3.24993 3.24993)
			(end -3.24993 3.24993)
			(stroke
				(width 0.1)
				(type default)
			)
			(layer "F.Fab")
		)
		(pad "1" smd rect
			(at -2.29997 0)
			(size 2.0066 4.2164)
			(layers "F.Cu" "F.Mask" "F.Paste")
			(net "SW_PVCCINFAON_CPU1_SW2")
		)
		(pad "2" smd rect
			(at 2.29997 0)
			(size 2.0066 4.2164)
			(layers "F.Cu" "F.Mask" "F.Paste")
			(net "PVCCINFAON_CPU1")
		)
	)
)
